# T6G (Grand Teton) — schematic netlist excerpt (pin names and nets, part order shuffled) for the footprints in the layout excerpt that follows; sources: Cadence DE-HDL packaged netlist, KiCad conversion of 04192023_DAF0TMB3IC0_F0TG_MB_C_brd_V02_OCP.brd

C73  Q_CAP  0.1UF 25V 10% X7R  pkg 0402  page 235 : A = P3V3_AUX ; B = GND

U273  LM75BD  IC  pkg SO8_1-27_4-9X3-9  page 235
  SDA  = SMB_LM75_3_3V3AUX_SDA_R1
  SCL  = SMB_LM75_3_3V3AUX_SCL_R1
  OS  = FM_LM75_3_ALERT_N
  GND  = GND
  A2  = U273_3_ADD2
  A1  = U273_3_ADD1
  A0  = U273_3_ADD0
  VCC  = P3V3_AUX

(kicad_pcb
	(version 20260206)
	(generator "pcbnew")
	(generator_version "10.0")
	(general
		(thickness 1.6)
		(legacy_teardrops no)
	)
	(paper "A4")
	(title_block
		(title "04192023_DAF0TMB3IC0_F0TG_MB_C_brd_V02_OCP.brd")
		(comment 1 "Grand Teton / footprints 2049-2050 of 8354")
	)
	(layers
		(0 "F.Cu" signal "TOP")
		(4 "In1.Cu" signal "GND")
		(6 "In2.Cu" signal "IN1")
		(8 "In3.Cu" signal "GND1")
		(10 "In4.Cu" signal "IN2")
		(12 "In5.Cu" signal "GND2")
		(14 "In6.Cu" signal "IN3")
		(16 "In7.Cu" signal "GND3")
		(18 "In8.Cu" signal "VCC")
		(20 "In9.Cu" signal "VCC1")
		(22 "In10.Cu" signal "GND4")
		(24 "In11.Cu" signal "IN4")
		(26 "In12.Cu" signal "GND5")
		(28 "In13.Cu" signal "IN5")
		(30 "In14.Cu" signal "GND6")
		(32 "In15.Cu" signal "IN6")
		(34 "In16.Cu" signal "GND7")
		(2 "B.Cu" signal "BOTTOM")
		(9 "F.Adhes" user "F.Adhesive")
		(11 "B.Adhes" user "B.Adhesive")
		(13 "F.Paste" user "Package Geometry/Pastemask Top")
		(15 "B.Paste" user "Package Geometry/Pastemask Bottom")
		(5 "F.SilkS" user "Ref Des/Silkscreen Top")
		(7 "B.SilkS" user "Ref Des/Silkscreen Bottom")
		(1 "F.Mask" user "Board Geometry/Soldermask Top")
		(3 "B.Mask" user "Board Geometry/Soldermask Bottom")
		(17 "Dwgs.User" user "User.Drawings")
		(19 "Cmts.User" user "User.Comments")
		(21 "Eco1.User" user "User.Eco1")
		(23 "Eco2.User" user "User.Eco2")
		(25 "Edge.Cuts" user "Board Geometry/Outline")
		(27 "Margin" user)
		(31 "F.CrtYd" user "Package Geometry/Place Bound Top")
		(29 "B.CrtYd" user "Package Geometry/Place Bound Bottom")
		(35 "F.Fab" user "Ref Des/Assembly Top")
		(33 "B.Fab" user "Ref Des/Assembly Bottom")
	)
	(footprint ""
		(layer "F.Cu")
		(at 294.769794 -18.780506 180)
		(property "Reference" "C73"
			(at 0 0 180)
			(layer "F.SilkS")
			(hide yes)
			(effects
				(font
					(size 1.27 1.27)
				)
			)
		)
		(property "Value" ""
			(at 0 0 180)
			(layer "F.Fab")
			(effects
				(font
					(size 1.27 1.27)
				)
			)
		)
		(duplicate_pad_numbers_are_jumpers no)
		(fp_line
			(start 0.7874 0.4064)
			(end -0.7874 0.4064)
			(stroke
				(width 0.1524)
				(type default)
			)
			(layer "F.SilkS")
		)
		(fp_line
			(start 0.7874 -0.4064)
			(end 0.7874 0.4064)
			(stroke
				(width 0.1524)
				(type default)
			)
			(layer "F.SilkS")
		)
		(fp_line
			(start -0.7874 0.4064)
			(end -0.7874 -0.4064)
			(stroke
				(width 0.1524)
				(type default)
			)
			(layer "F.SilkS")
		)
		(fp_line
			(start -0.7874 -0.4064)
			(end 0.7874 -0.4064)
			(stroke
				(width 0.1524)
				(type default)
			)
			(layer "F.SilkS")
		)
		(fp_line
			(start 0.67945 0.3048)
			(end 0.120396 0.3048)
			(stroke
				(width 0.1)
				(type default)
			)
			(layer "F.Fab")
		)
		(fp_line
			(start 0.67945 -0.3048)
			(end 0.67945 0.3048)
			(stroke
				(width 0.1)
				(type default)
			)
			(layer "F.Fab")
		)
		(fp_line
			(start 0.12065 -0.2794)
			(end 0.12065 -0.3048)
			(stroke
				(width 0.1)
				(type default)
			)
			(layer "F.Fab")
		)
		(fp_line
			(start 0.12065 -0.3048)
			(end 0.67945 -0.3048)
			(stroke
				(width 0.1)
				(type default)
			)
			(layer "F.Fab")
		)
		(fp_line
			(start 0.120396 0.3048)
			(end 0.120396 0.2794)
			(stroke
				(width 0.1)
				(type default)
			)
			(layer "F.Fab")
		)
		(fp_line
			(start 0.120396 0.2794)
			(end -0.12065 0.2794)
			(stroke
				(width 0.1)
				(type default)
			)
			(layer "F.Fab")
		)
		(fp_line
			(start -0.12065 0.3048)
			(end -0.67945 0.3048)
			(stroke
				(width 0.1)
				(type default)
			)
			(layer "F.Fab")
		)
		(fp_line
			(start -0.12065 0.2794)
			(end -0.12065 0.3048)
			(stroke
				(width 0.1)
				(type default)
			)
			(layer "F.Fab")
		)
		(fp_line
			(start -0.12065 -0.2794)
			(end 0.12065 -0.2794)
			(stroke
				(width 0.1)
				(type default)
			)
			(layer "F.Fab")
		)
		(fp_line
			(start -0.12065 -0.305054)
			(end -0.12065 -0.2794)
			(stroke
				(width 0.1)
				(type default)
			)
			(layer "F.Fab")
		)
		(fp_line
			(start -0.67945 0.3048)
			(end -0.67945 -0.305054)
			(stroke
				(width 0.1)
				(type default)
			)
			(layer "F.Fab")
		)
		(fp_line
			(start -0.67945 -0.305054)
			(end -0.12065 -0.305054)
			(stroke
				(width 0.1)
				(type default)
			)
			(layer "F.Fab")
		)
		(pad "1" smd circle
			(at -0.40005 0 180)
			(size 0 0)
			(layers "F.Cu" "F.Mask" "F.Paste")
			(net "P3V3_AUX")
		)
		(pad "2" smd circle
			(at 0.40005 0 180)
			(size 0 0)
			(layers "F.Cu" "F.Mask" "F.Paste")
			(net "GND")
		)
	)
	(footprint ""
		(layer "F.Cu")
		(at 113.20653 -15.879064)
		(property "Reference" "U273"
			(at 1.29413 -3.490214 0)
			(unlocked yes)
			(layer "F.SilkS")
			(effects
				(font
					(size 0.7874 0.5842)
					(thickness 0.1524)
				)
				(justify left)
			)
		)
		(property "Value" ""
			(at 0 0 0)
			(layer "F.Fab")
			(effects
				(font
					(size 1.27 1.27)
				)
			)
		)
		(duplicate_pad_numbers_are_jumpers no)
		(fp_line
			(start -3.447796 -2.500122)
			(end -3.447796 2.500122)
			(stroke
				(width 0.1524)
				(type default)
			)
			(layer "F.SilkS")
		)
		(fp_line
			(start -3.447796 2.500122)
			(end 3.447796 2.500122)
			(stroke
				(width 0.1524)
				(type default)
			)
			(layer "F.SilkS")
		)
		(fp_line
			(start -1.484122 -2.500122)
			(end -3.447796 -2.500122)
			(stroke
				(width 0.1524)
				(type default)
			)
			(layer "F.SilkS")
		)
		(fp_line
			(start 0 -1.016)
			(end -1.484122 -2.500122)
			(stroke
				(width 0.1524)
				(type default)
			)
			(layer "F.SilkS")
		)
		(fp_line
			(start 1.484122 -2.500122)
			(end 0 -1.016)
			(stroke
				(width 0.1524)
				(type default)
			)
			(layer "F.SilkS")
		)
		(fp_line
			(start 3.447796 -2.500122)
			(end 1.484122 -2.500122)
			(stroke
				(width 0.1524)
				(type default)
			)
			(layer "F.SilkS")
		)
		(fp_line
			(start 3.447796 2.500122)
			(end 3.447796 -2.500122)
			(stroke
				(width 0.1524)
				(type default)
			)
			(layer "F.SilkS")
		)
		(fp_poly
			(pts
				(xy -4.670552 -0.917702) (xy -4.901184 -1.907032) (xy -3.796538 -1.64338)
			)
			(stroke
				(width 0)
				(type default)
			)
			(fill yes)
			(layer "F.SilkS")
		)
		(fp_line
			(start -1.999996 -2.500122)
			(end -1.999996 2.500122)
			(stroke
				(width 0.1)
				(type default)
			)
			(layer "F.Fab")
		)
		(fp_line
			(start -1.999996 2.500122)
			(end 1.999996 2.500122)
			(stroke
				(width 0.1)
				(type default)
			)
			(layer "F.Fab")
		)
		(fp_line
			(start 1.999996 -2.500122)
			(end -1.999996 -2.500122)
			(stroke
				(width 0.1)
				(type default)
			)
			(layer "F.Fab")
		)
		(fp_line
			(start 1.999996 2.500122)
			(end 1.999996 -2.500122)
			(stroke
				(width 0.1)
				(type default)
			)
			(layer "F.Fab")
		)
		(fp_poly
			(pts
				(xy -4.5974 -2.413) (xy -4.5974 -1.397) (xy -3.5814 -1.905)
			)
			(stroke
				(width 0)
				(type default)
			)
			(fill yes)
			(layer "F.Fab")
		)
		(pad "1" smd rect
			(at -2.649982 -1.905 270)
			(size 0.6096 1.3208)
			(layers "F.Cu" "F.Mask" "F.Paste")
			(net "SMB_LM75_3_3V3AUX_SDA_R1")
		)
		(pad "2" smd rect
			(at -2.649982 -0.635 270)
			(size 0.6096 1.3208)
			(layers "F.Cu" "F.Mask" "F.Paste")
			(net "SMB_LM75_3_3V3AUX_SCL_R1")
		)
		(pad "3" smd rect
			(at -2.649982 0.635 270)
			(size 0.6096 1.3208)
			(layers "F.Cu" "F.Mask" "F.Paste")
			(net "FM_LM75_3_ALERT_N")
		)
		(pad "4" smd rect
			(at -2.649982 1.905 270)
			(size 0.6096 1.3208)
			(layers "F.Cu" "F.Mask" "F.Paste")
			(net "GND")
		)
		(pad "5" smd rect
			(at 2.649982 1.905 270)
			(size 0.6096 1.3208)
			(layers "F.Cu" "F.Mask" "F.Paste")
			(net "U273_3_ADD2")
		)
		(pad "6" smd rect
			(at 2.649982 0.635 270)
			(size 0.6096 1.3208)
			(layers "F.Cu" "F.Mask" "F.Paste")
			(net "U273_3_ADD1")
		)
		(pad "7" smd rect
			(at 2.649982 -0.635 270)
			(size 0.6096 1.3208)
			(layers "F.Cu" "F.Mask" "F.Paste")
			(net "U273_3_ADD0")
		)
		(pad "8" smd rect
			(at 2.649982 -1.905 270)
			(size 0.6096 1.3208)
			(layers "F.Cu" "F.Mask" "F.Paste")
			(net "P3V3_AUX")
		)
	)
)
